# S9S_MB_2U (Grand Teton) — schematic netlist excerpt (pin names and nets, part order shuffled) for the footprints in the layout excerpt that follows; sources: Cadence DE-HDL packaged netlist, KiCad conversion of 03242023_DA0F0TMBIJ0_F0T_Motherboard_J_brd_V01_OCP.brd

PU29  RAA229126GNPHA0  RAA229126GNP#HA0 IC  pkg QFN48_THXT  page 284
  PWM0  = PVCCFA_EHV_FIVRA_CPU1_PWM1
  PWM1  = PVCCFA_EHV_FIVRA_CPU1_PWM2
  PWM2  = PVCCFA_EHV_FIVRA_CPU1_PWM3
  PWM3  = PVCCFA_EHV_FIVRA_CPU1_PWM4
  PWM4  = PVCCIN_CPU1_PWM8
  PWM5  = PVCCIN_CPU1_PWM7
  PWM6  = PVCCIN_CPU1_PWM6
  PWM7  = PVCCIN_CPU1_PWM5
  PWM8  = PVCCIN_CPU1_PWM4
  PWM9  = PVCCIN_CPU1_PWM3
  PWM10  = PVCCIN_CPU1_PWM2
  PWM11  = PVCCIN_CPU1_PWM1
  PMSDA  = SMB_DIO_PVCCIN_CPU1
  PMSCL  = SMB_CLK_PVCCIN_CPU1
  NPMALERT  = NC_PVCCIN_CPU1_SMB_ALERT
  PG0  = PWRGD_PVCCIN_CPU1_R
  EN0  = PVCCIN_CPU1_EN_R
  NVRHOT  = IRQ_PVCCIN_CPU1_VRHOT_N
  \npinalert||npsys_crit\  = PVCCIN_CPU1_PIN_ALERT
  PG1  = PWRGD_PVCCFA_EHV_FIVRA_CPU1_R
  SVCLK  = SVID_CLK_PVCCIN_CPU1_R
  SVDATA  = SVID_DIO_PVCCIN_CPU1_R
  NSVALERT  = SVID_ALERT_PVCCIN_CPU1_R
  EN1  = PVCCFA_EHV_FIVRA_CPU1_EN_R
  VSEN0  = SH_PVCCIN_CPU1_R
  RGND0  = VSENSE_PVCCIN_CPU1_DN
  CS11  = PVCCIN_CPU1_IMON1
  CS10  = PVCCIN_CPU1_IMON2
  CS9  = PVCCIN_CPU1_IMON3
  CS8  = PVCCIN_CPU1_IMON4
  CS7  = PVCCIN_CPU1_IMON5
  CS6  = PVCCIN_CPU1_IMON6
  CS5  = PVCCIN_CPU1_IMON7
  CS4  = PVCCIN_CPU1_IMON8
  CS3  = PVCCFA_EHV_FIVRA_CPU1_IMON4
  CS2  = PVCCFA_EHV_FIVRA_CPU1_IMON3
  CS1  = PVCCFA_EHV_FIVRA_CPU1_IMON2
  CS0  = PVCCFA_EHV_FIVRA_CPU1_IMON1
  RGND1  = VSENSE_PVCCFA_EHV_FIVRA_CPU1_DN
  VSEN1  = SH_PVCCFA_EHV_FIVRA_CPU1_R
  CFP  = PVCCIN_CPU1_VR_FAULT
  ADDR_CFG  = PVCCIN_CPU1_ADDR
  TEMP0  = PVCCIN_CPU1_ATSEN
  \temp1||isys\  = PVCCFA_EHV_FIVRA_CPU1_BTSEN
  \vmon||iinsen||vsys||isys\  = PVCCIN_CPU1_CSPIN
  \vinsen||vsys\  = PVCCIN_CPU1_VIN_CSNIN
  VCC  = PVCCIN_CPU1_VCC
  VCCS  = PVCCIN_CPU1_VREF
  TH_GND  = GND

(kicad_pcb
	(version 20260206)
	(generator "pcbnew")
	(generator_version "10.0")
	(general
		(thickness 1.6)
		(legacy_teardrops no)
	)
	(paper "A4")
	(title_block
		(title "03242023_DA0F0TMBIJ0_F0T_Motherboard_J_brd_V01_OCP.brd")
		(comment 1 "Grand Teton / footprint 2465 of 6105 (PU29), pads 43-49 of 49")
	)
	(layers
		(0 "F.Cu" signal "TOP")
		(4 "In1.Cu" signal "GND")
		(6 "In2.Cu" signal "IN1")
		(8 "In3.Cu" signal "GND1")
		(10 "In4.Cu" signal "IN2")
		(12 "In5.Cu" signal "GND2")
		(14 "In6.Cu" signal "IN3")
		(16 "In7.Cu" signal "GND3")
		(18 "In8.Cu" signal "VCC")
		(20 "In9.Cu" signal "VCC1")
		(22 "In10.Cu" signal "GND4")
		(24 "In11.Cu" signal "IN4")
		(26 "In12.Cu" signal "GND5")
		(28 "In13.Cu" signal "IN5")
		(30 "In14.Cu" signal "GND6")
		(32 "In15.Cu" signal "IN6")
		(34 "In16.Cu" signal "GND7")
		(2 "B.Cu" signal "BOTTOM")
		(9 "F.Adhes" user "F.Adhesive")
		(11 "B.Adhes" user "B.Adhesive")
		(13 "F.Paste" user "Package Geometry/Pastemask Top")
		(15 "B.Paste" user "Package Geometry/Pastemask Bottom")
		(5 "F.SilkS" user "Ref Des/Silkscreen Top")
		(7 "B.SilkS" user "Ref Des/Silkscreen Bottom")
		(1 "F.Mask" user "Board Geometry/Soldermask Top")
		(3 "B.Mask" user "Board Geometry/Soldermask Bottom")
		(17 "Dwgs.User" user "User.Drawings")
		(19 "Cmts.User" user "User.Comments")
		(21 "Eco1.User" user "User.Eco1")
		(23 "Eco2.User" user "User.Eco2")
		(25 "Edge.Cuts" user "Board Geometry/Outline")
		(27 "Margin" user)
		(31 "F.CrtYd" user "Package Geometry/Place Bound Top")
		(29 "B.CrtYd" user "Package Geometry/Place Bound Bottom")
		(35 "F.Fab" user "Ref Des/Assembly Top")
		(33 "B.Fab" user "Ref Des/Assembly Bottom")
	)
	(footprint ""
		(layer "F.Cu")
		(at 108.578396 -358.848406 -90)
		(property "Reference" "PU29"
			(at 8.473948 -1.629664 0)
			(unlocked yes)
			(layer "F.SilkS")
			(effects
				(font
					(size 0.7874 0.5842)
					(thickness 0.1524)
				)
				(justify left)
			)
		)
		(property "Value" ""
			(at 0 0 270)
			(layer "F.Fab")
			(effects
				(font
					(size 1.27 1.27)
				)
			)
		)
		(duplicate_pad_numbers_are_jumpers no)
		(pad "43" smd rect
			(at -0.199898 -2.875026 270)
			(size 0.1778 0.6604)
			(layers "F.Cu" "F.Mask" "F.Paste")
			(net "PVCCIN_CPU1_ATSEN")
		)
		(pad "44" smd rect
			(at -0.599948 -2.875026 270)
			(size 0.1778 0.6604)
			(layers "F.Cu" "F.Mask" "F.Paste")
			(net "PVCCFA_EHV_FIVRA_CPU1_BTSEN")
		)
		(pad "45" smd rect
			(at -0.999998 -2.875026 270)
			(size 0.1778 0.6604)
			(layers "F.Cu" "F.Mask" "F.Paste")
			(net "PVCCIN_CPU1_CSPIN")
		)
		(pad "46" smd rect
			(at -1.400048 -2.875026 270)
			(size 0.1778 0.6604)
			(layers "F.Cu" "F.Mask" "F.Paste")
			(net "PVCCIN_CPU1_VIN_CSNIN")
		)
		(pad "47" smd rect
			(at -1.800098 -2.875026 270)
			(size 0.1778 0.6604)
			(layers "F.Cu" "F.Mask" "F.Paste")
			(net "PVCCIN_CPU1_VCC")
		)
		(pad "48" smd rect
			(at -2.199894 -2.875026 270)
			(size 0.1778 0.6604)
			(layers "F.Cu" "F.Mask" "F.Paste")
			(net "PVCCIN_CPU1_VREF")
		)
		(pad "TH" smd rect
			(at 0 0 270)
			(size 4.4196 4.4196)
			(layers "F.Cu" "F.Mask" "F.Paste")
			(net "GND")
		)
	)
)
